# T6G (Grand Teton) — schematic netlist excerpt (pin names and nets, part order shuffled) for the footprints in the layout excerpt that follows; sources: Cadence DE-HDL packaged netlist, KiCad conversion of 04192023_DAF0TMB3IC0_F0TG_MB_C_brd_V02_OCP.brd

R431  Q_RES  0 5% CHIP  pkg 0402LF  page 28 : A = SMB_CPU0_4_R_SDA ; B = SMB_CPU0_4_SDA
C23  Q_CAP  0.1UF 25V 10% X7R  pkg 0402  page 160 : A = P3V3_AUX ; B = GND

(kicad_pcb
	(version 20260206)
	(generator "pcbnew")
	(generator_version "10.0")
	(general
		(thickness 1.6)
		(legacy_teardrops no)
	)
	(paper "A4")
	(title_block
		(title "04192023_DAF0TMB3IC0_F0TG_MB_C_brd_V02_OCP.brd")
		(comment 1 "Grand Teton / footprints 7887-7888 of 8354")
	)
	(layers
		(0 "F.Cu" signal "TOP")
		(4 "In1.Cu" signal "GND")
		(6 "In2.Cu" signal "IN1")
		(8 "In3.Cu" signal "GND1")
		(10 "In4.Cu" signal "IN2")
		(12 "In5.Cu" signal "GND2")
		(14 "In6.Cu" signal "IN3")
		(16 "In7.Cu" signal "GND3")
		(18 "In8.Cu" signal "VCC")
		(20 "In9.Cu" signal "VCC1")
		(22 "In10.Cu" signal "GND4")
		(24 "In11.Cu" signal "IN4")
		(26 "In12.Cu" signal "GND5")
		(28 "In13.Cu" signal "IN5")
		(30 "In14.Cu" signal "GND6")
		(32 "In15.Cu" signal "IN6")
		(34 "In16.Cu" signal "GND7")
		(2 "B.Cu" signal "BOTTOM")
		(9 "F.Adhes" user "F.Adhesive")
		(11 "B.Adhes" user "B.Adhesive")
		(13 "F.Paste" user "Package Geometry/Pastemask Top")
		(15 "B.Paste" user "Package Geometry/Pastemask Bottom")
		(5 "F.SilkS" user "Ref Des/Silkscreen Top")
		(7 "B.SilkS" user "Ref Des/Silkscreen Bottom")
		(1 "F.Mask" user "Board Geometry/Soldermask Top")
		(3 "B.Mask" user "Board Geometry/Soldermask Bottom")
		(17 "Dwgs.User" user "User.Drawings")
		(19 "Cmts.User" user "User.Comments")
		(21 "Eco1.User" user "User.Eco1")
		(23 "Eco2.User" user "User.Eco2")
		(25 "Edge.Cuts" user "Board Geometry/Outline")
		(27 "Margin" user)
		(31 "F.CrtYd" user "Package Geometry/Place Bound Top")
		(29 "B.CrtYd" user "Package Geometry/Place Bound Bottom")
		(35 "F.Fab" user "Ref Des/Assembly Top")
		(33 "B.Fab" user "Ref Des/Assembly Bottom")
	)
	(footprint ""
		(layer "B.Cu")
		(at 405.086058 -319.748916 -90)
		(property "Reference" "R431"
			(at 0 0 90)
			(layer "B.SilkS")
			(hide yes)
			(effects
				(font
					(size 1.27 1.27)
				)
				(justify mirror)
			)
		)
		(property "Value" ""
			(at 0 0 90)
			(layer "B.Fab")
			(effects
				(font
					(size 1.27 1.27)
				)
				(justify mirror)
			)
		)
		(duplicate_pad_numbers_are_jumpers no)
		(fp_line
			(start -0.7874 0.4064)
			(end 0.7874 0.4064)
			(stroke
				(width 0.1524)
				(type default)
			)
			(layer "B.SilkS")
		)
		(fp_line
			(start 0.7874 0.4064)
			(end 0.7874 -0.4064)
			(stroke
				(width 0.1524)
				(type default)
			)
			(layer "B.SilkS")
		)
		(fp_line
			(start -0.7874 -0.4064)
			(end -0.7874 0.4064)
			(stroke
				(width 0.1524)
				(type default)
			)
			(layer "B.SilkS")
		)
		(fp_line
			(start 0.7874 -0.4064)
			(end -0.7874 -0.4064)
			(stroke
				(width 0.1524)
				(type default)
			)
			(layer "B.SilkS")
		)
		(fp_line
			(start -0.67945 0.3048)
			(end -0.120396 0.3048)
			(stroke
				(width 0.1)
				(type default)
			)
			(layer "B.Fab")
		)
		(fp_line
			(start -0.120396 0.3048)
			(end -0.120396 0.2794)
			(stroke
				(width 0.1)
				(type default)
			)
			(layer "B.Fab")
		)
		(fp_line
			(start 0.12065 0.3048)
			(end 0.67945 0.3048)
			(stroke
				(width 0.1)
				(type default)
			)
			(layer "B.Fab")
		)
		(fp_line
			(start 0.67945 0.3048)
			(end 0.67945 -0.305054)
			(stroke
				(width 0.1)
				(type default)
			)
			(layer "B.Fab")
		)
		(fp_line
			(start -0.120396 0.2794)
			(end 0.12065 0.2794)
			(stroke
				(width 0.1)
				(type default)
			)
			(layer "B.Fab")
		)
		(fp_line
			(start 0.12065 0.2794)
			(end 0.12065 0.3048)
			(stroke
				(width 0.1)
				(type default)
			)
			(layer "B.Fab")
		)
		(fp_line
			(start -0.12065 -0.2794)
			(end -0.12065 -0.3048)
			(stroke
				(width 0.1)
				(type default)
			)
			(layer "B.Fab")
		)
		(fp_line
			(start 0.12065 -0.2794)
			(end -0.12065 -0.2794)
			(stroke
				(width 0.1)
				(type default)
			)
			(layer "B.Fab")
		)
		(fp_line
			(start -0.67945 -0.3048)
			(end -0.67945 0.3048)
			(stroke
				(width 0.1)
				(type default)
			)
			(layer "B.Fab")
		)
		(fp_line
			(start -0.12065 -0.3048)
			(end -0.67945 -0.3048)
			(stroke
				(width 0.1)
				(type default)
			)
			(layer "B.Fab")
		)
		(fp_line
			(start 0.12065 -0.305054)
			(end 0.12065 -0.2794)
			(stroke
				(width 0.1)
				(type default)
			)
			(layer "B.Fab")
		)
		(fp_line
			(start 0.67945 -0.305054)
			(end 0.12065 -0.305054)
			(stroke
				(width 0.1)
				(type default)
			)
			(layer "B.Fab")
		)
		(pad "1" smd circle
			(at 0.40005 0 90)
			(size 0 0)
			(layers "B.Cu" "B.Mask" "B.Paste")
			(net "SMB_CPU0_4_R_SDA")
		)
		(pad "2" smd circle
			(at -0.40005 0 90)
			(size 0 0)
			(layers "B.Cu" "B.Mask" "B.Paste")
			(net "SMB_CPU0_4_SDA")
		)
	)
	(footprint ""
		(layer "B.Cu")
		(at 236.119162 -224.515934 -90)
		(property "Reference" "C23"
			(at 0 0 90)
			(layer "B.SilkS")
			(hide yes)
			(effects
				(font
					(size 1.27 1.27)
				)
				(justify mirror)
			)
		)
		(property "Value" ""
			(at 0 0 90)
			(layer "B.Fab")
			(effects
				(font
					(size 1.27 1.27)
				)
				(justify mirror)
			)
		)
		(duplicate_pad_numbers_are_jumpers no)
		(fp_line
			(start -0.7874 0.4064)
			(end 0.7874 0.4064)
			(stroke
				(width 0.1524)
				(type default)
			)
			(layer "B.SilkS")
		)
		(fp_line
			(start 0.7874 0.4064)
			(end 0.7874 -0.4064)
			(stroke
				(width 0.1524)
				(type default)
			)
			(layer "B.SilkS")
		)
		(fp_line
			(start -0.7874 -0.4064)
			(end -0.7874 0.4064)
			(stroke
				(width 0.1524)
				(type default)
			)
			(layer "B.SilkS")
		)
		(fp_line
			(start 0.7874 -0.4064)
			(end -0.7874 -0.4064)
			(stroke
				(width 0.1524)
				(type default)
			)
			(layer "B.SilkS")
		)
		(fp_line
			(start -0.67945 0.3048)
			(end -0.120396 0.3048)
			(stroke
				(width 0.1)
				(type default)
			)
			(layer "B.Fab")
		)
		(fp_line
			(start -0.120396 0.3048)
			(end -0.120396 0.2794)
			(stroke
				(width 0.1)
				(type default)
			)
			(layer "B.Fab")
		)
		(fp_line
			(start 0.12065 0.3048)
			(end 0.67945 0.3048)
			(stroke
				(width 0.1)
				(type default)
			)
			(layer "B.Fab")
		)
		(fp_line
			(start 0.67945 0.3048)
			(end 0.67945 -0.305054)
			(stroke
				(width 0.1)
				(type default)
			)
			(layer "B.Fab")
		)
		(fp_line
			(start -0.120396 0.2794)
			(end 0.12065 0.2794)
			(stroke
				(width 0.1)
				(type default)
			)
			(layer "B.Fab")
		)
		(fp_line
			(start 0.12065 0.2794)
			(end 0.12065 0.3048)
			(stroke
				(width 0.1)
				(type default)
			)
			(layer "B.Fab")
		)
		(fp_line
			(start -0.12065 -0.2794)
			(end -0.12065 -0.3048)
			(stroke
				(width 0.1)
				(type default)
			)
			(layer "B.Fab")
		)
		(fp_line
			(start 0.12065 -0.2794)
			(end -0.12065 -0.2794)
			(stroke
				(width 0.1)
				(type default)
			)
			(layer "B.Fab")
		)
		(fp_line
			(start -0.67945 -0.3048)
			(end -0.67945 0.3048)
			(stroke
				(width 0.1)
				(type default)
			)
			(layer "B.Fab")
		)
		(fp_line
			(start -0.12065 -0.3048)
			(end -0.67945 -0.3048)
			(stroke
				(width 0.1)
				(type default)
			)
			(layer "B.Fab")
		)
		(fp_line
			(start 0.12065 -0.305054)
			(end 0.12065 -0.2794)
			(stroke
				(width 0.1)
				(type default)
			)
			(layer "B.Fab")
		)
		(fp_line
			(start 0.67945 -0.305054)
			(end 0.12065 -0.305054)
			(stroke
				(width 0.1)
				(type default)
			)
			(layer "B.Fab")
		)
		(pad "1" smd circle
			(at 0.40005 0 90)
			(size 0 0)
			(layers "B.Cu" "B.Mask" "B.Paste")
			(net "P3V3_AUX")
		)
		(pad "2" smd circle
			(at -0.40005 0 90)
			(size 0 0)
			(layers "B.Cu" "B.Mask" "B.Paste")
			(net "GND")
		)
	)
)
